(kicad_pcb
	(version 20260206)
	(generator "pcbnew")
	(generator_version "10.0")
	(general
		(thickness 1.6)
		(legacy_teardrops no)
	)
	(paper "A4")
	(title_block
		(title "Wiwynn_Tioga_Pass_MB.brd")
		(comment 1 "Tioga Pass / footprints 1696-1700 of 4770")
	)
	(layers
		(0 "F.Cu" signal "TOP")
		(4 "In1.Cu" signal "L2GND")
		(6 "In2.Cu" signal "L3")
		(8 "In3.Cu" signal "L4GND")
		(10 "In4.Cu" signal "L5")
		(12 "In5.Cu" signal "L6GND")
		(14 "In6.Cu" signal "L7VCC")
		(16 "In7.Cu" signal "L8VCC")
		(18 "In8.Cu" signal "L9GND")
		(20 "In9.Cu" signal "L10")
		(22 "In10.Cu" signal "L11GND")
		(24 "In11.Cu" signal "L12")
		(26 "In12.Cu" signal "L13GND")
		(2 "B.Cu" signal "BOTTOM")
		(9 "F.Adhes" user "F.Adhesive")
		(11 "B.Adhes" user "B.Adhesive")
		(13 "F.Paste" user "Package Geometry/Pastemask Top")
		(15 "B.Paste" user "Package Geometry/Pastemask Bottom")
		(5 "F.SilkS" user "Ref Des/Silkscreen Top")
		(7 "B.SilkS" user "Ref Des/Silkscreen Bottom")
		(1 "F.Mask" user "Board Geometry/Soldermask Top")
		(3 "B.Mask" user "Board Geometry/Soldermask Bottom")
		(17 "Dwgs.User" user "User.Drawings")
		(19 "Cmts.User" user "User.Comments")
		(21 "Eco1.User" user "User.Eco1")
		(23 "Eco2.User" user "User.Eco2")
		(25 "Edge.Cuts" user "Board Geometry/Outline")
		(27 "Margin" user)
		(31 "F.CrtYd" user "Package Geometry/Place Bound Top")
		(29 "B.CrtYd" user "Package Geometry/Place Bound Bottom")
		(35 "F.Fab" user "Ref Des/Assembly Top")
		(33 "B.Fab" user "Ref Des/Assembly Bottom")
	)
	(footprint ""
		(layer "F.Cu")
		(at 28.851352 -64.089788 -90)
		(property "Reference" "R1E13"
			(at 0 0 270)
			(layer "F.SilkS")
			(hide yes)
			(effects
				(font
					(size 1.27 1.27)
				)
			)
		)
		(property "Value" ""
			(at 0 0 270)
			(layer "F.Fab")
			(effects
				(font
					(size 1.27 1.27)
				)
			)
		)
		(duplicate_pad_numbers_are_jumpers no)
		(fp_poly
			(pts
				(xy -0.2794 -0.1016) (xy 0.2794 -0.1016) (xy 0.2794 0.9906) (xy -0.2794 0.9906)
			)
			(stroke
				(width 0)
				(type default)
			)
			(fill no)
			(layer "F.CrtYd")
		)
		(fp_line
			(start -0.2794 0.9906)
			(end 0.2794 0.9906)
			(stroke
				(width 0.1)
				(type default)
			)
			(layer "F.Fab")
		)
		(fp_line
			(start 0.2794 0.9906)
			(end 0.2794 -0.1016)
			(stroke
				(width 0.1)
				(type default)
			)
			(layer "F.Fab")
		)
		(fp_line
			(start -0.2794 -0.1016)
			(end -0.2794 0.9906)
			(stroke
				(width 0.1)
				(type default)
			)
			(layer "F.Fab")
		)
		(fp_line
			(start 0.2794 -0.1016)
			(end -0.2794 -0.1016)
			(stroke
				(width 0.1)
				(type default)
			)
			(layer "F.Fab")
		)
		(pad "1" smd rect
			(at 0 0 270)
			(size 0.508 0.508)
			(layers "F.Cu" "F.Mask" "F.Paste")
			(net "VR_PVCCIN_CPU1_PH2_OCSET")
		)
		(pad "2" smd rect
			(at 0 0.889 270)
			(size 0.508 0.508)
			(layers "F.Cu" "F.Mask" "F.Paste")
			(net "GND")
		)
		(zone
			(layer "F.Cu")
			(hatch none 0.5)
			(connect_pads
				(clearance 0)
			)
			(min_thickness 0.25)
			(keepout
				(tracks not_allowed)
				(vias allowed)
				(pads allowed)
				(copperpour not_allowed)
				(footprints allowed)
			)
			(placement
				(enabled no)
				(sheetname "")
			)
			(fill
				(thermal_gap 0.5)
				(thermal_bridge_width 0.5)
				(island_removal_mode 0)
			)
			(polygon
				(pts
					(xy 28.216352 -64.343788) (xy 28.216352 -63.835788) (xy 28.597352 -63.835788) (xy 28.597352 -64.343788)
				)
			)
		)
		(zone
			(layer "F.Cu")
			(hatch none 0.5)
			(connect_pads
				(clearance 0)
			)
			(min_thickness 0.25)
			(keepout
				(tracks allowed)
				(vias not_allowed)
				(pads allowed)
				(copperpour not_allowed)
				(footprints allowed)
			)
			(placement
				(enabled no)
				(sheetname "")
			)
			(fill
				(thermal_gap 0.5)
				(thermal_bridge_width 0.5)
				(island_removal_mode 0)
			)
			(polygon
				(pts
					(xy 28.597352 -64.343788) (xy 28.597352 -63.835788) (xy 28.216352 -63.835788) (xy 28.216352 -64.343788)
				)
			)
		)
	)
	(footprint ""
		(layer "F.Cu")
		(at 347.113606 -2.127504 -90)
		(property "Reference" "C7G41"
			(at 0 0 270)
			(layer "F.SilkS")
			(hide yes)
			(effects
				(font
					(size 1.27 1.27)
				)
			)
		)
		(property "Value" ""
			(at 0 0 270)
			(layer "F.Fab")
			(effects
				(font
					(size 1.27 1.27)
				)
			)
		)
		(duplicate_pad_numbers_are_jumpers no)
		(fp_rect
			(start -0.3048 -0.1016)
			(end 0.3048 0.9906)
			(stroke
				(width 0)
				(type default)
			)
			(fill no)
			(layer "F.CrtYd")
		)
		(fp_line
			(start -0.3048 0.9906)
			(end 0.3048 0.9906)
			(stroke
				(width 0.1)
				(type default)
			)
			(layer "F.Fab")
		)
		(fp_line
			(start 0.3048 0.9906)
			(end 0.3048 -0.1016)
			(stroke
				(width 0.1)
				(type default)
			)
			(layer "F.Fab")
		)
		(fp_line
			(start -0.3048 -0.1016)
			(end -0.3048 0.9906)
			(stroke
				(width 0.1)
				(type default)
			)
			(layer "F.Fab")
		)
		(fp_line
			(start 0.3048 -0.1016)
			(end -0.3048 -0.1016)
			(stroke
				(width 0.1)
				(type default)
			)
			(layer "F.Fab")
		)
		(pad "1" smd rect
			(at 0 0 270)
			(size 0.508 0.508)
			(layers "F.Cu" "F.Mask" "F.Paste")
			(net "P5V_STBY")
		)
		(pad "2" smd rect
			(at 0 0.889 270)
			(size 0.508 0.508)
			(layers "F.Cu" "F.Mask" "F.Paste")
			(net "GND")
		)
		(zone
			(layer "F.Cu")
			(hatch none 0.5)
			(connect_pads
				(clearance 0)
			)
			(min_thickness 0.25)
			(keepout
				(tracks allowed)
				(vias not_allowed)
				(pads allowed)
				(copperpour not_allowed)
				(footprints allowed)
			)
			(placement
				(enabled no)
				(sheetname "")
			)
			(fill
				(thermal_gap 0.5)
				(thermal_bridge_width 0.5)
				(island_removal_mode 0)
			)
			(polygon
				(pts
					(xy 346.859606 -2.381504) (xy 346.478606 -2.381504) (xy 346.478606 -1.873504) (xy 346.859606 -1.873504)
				)
			)
		)
		(zone
			(layer "F.Cu")
			(hatch none 0.5)
			(connect_pads
				(clearance 0)
			)
			(min_thickness 0.25)
			(keepout
				(tracks not_allowed)
				(vias allowed)
				(pads allowed)
				(copperpour not_allowed)
				(footprints allowed)
			)
			(placement
				(enabled no)
				(sheetname "")
			)
			(fill
				(thermal_gap 0.5)
				(thermal_bridge_width 0.5)
				(island_removal_mode 0)
			)
			(polygon
				(pts
					(xy 346.859606 -2.381504) (xy 346.478606 -2.381504) (xy 346.478606 -1.873504) (xy 346.859606 -1.873504)
				)
			)
		)
	)
	(footprint ""
		(layer "F.Cu")
		(at 337.7311 -134.493 -90)
		(property "Reference" "L7B1"
			(at 5.08 6.99643 90)
			(unlocked yes)
			(layer "F.SilkS")
			(effects
				(font
					(size 0.7874 0.5842)
					(thickness 0.1524)
				)
				(justify left)
			)
		)
		(property "Value" ""
			(at 0 0 270)
			(layer "F.Fab")
			(effects
				(font
					(size 1.27 1.27)
				)
			)
		)
		(duplicate_pad_numbers_are_jumpers no)
		(fp_line
			(start -3.4036 6.1341)
			(end -3.4036 -0.6731)
			(stroke
				(width 0.1524)
				(type default)
			)
			(layer "F.SilkS")
		)
		(fp_line
			(start -2.5654 6.1341)
			(end -3.4036 6.1341)
			(stroke
				(width 0.1524)
				(type default)
			)
			(layer "F.SilkS")
		)
		(fp_line
			(start 3.4036 6.1341)
			(end 2.5654 6.1341)
			(stroke
				(width 0.1524)
				(type default)
			)
			(layer "F.SilkS")
		)
		(fp_line
			(start -3.4036 -0.6731)
			(end -2.5654 -0.6731)
			(stroke
				(width 0.1524)
				(type default)
			)
			(layer "F.SilkS")
		)
		(fp_line
			(start 2.5654 -0.6731)
			(end 3.4036 -0.6731)
			(stroke
				(width 0.1524)
				(type default)
			)
			(layer "F.SilkS")
		)
		(fp_line
			(start 3.4036 -0.6731)
			(end 3.4036 6.1341)
			(stroke
				(width 0.1524)
				(type default)
			)
			(layer "F.SilkS")
		)
		(fp_poly
			(pts
				(xy -3.4036 -0.6731) (xy -3.4036 6.1341) (xy 3.4036 6.1341) (xy 3.4036 -0.6731)
			)
			(stroke
				(width 0)
				(type default)
			)
			(fill no)
			(layer "F.CrtYd")
		)
		(fp_line
			(start -3.4036 6.1341)
			(end -3.4036 -0.6731)
			(stroke
				(width 0.1)
				(type default)
			)
			(layer "F.Fab")
		)
		(fp_line
			(start 3.4036 6.1341)
			(end -3.4036 6.1341)
			(stroke
				(width 0.1)
				(type default)
			)
			(layer "F.Fab")
		)
		(fp_line
			(start -3.4036 -0.6731)
			(end 3.4036 -0.6731)
			(stroke
				(width 0.1)
				(type default)
			)
			(layer "F.Fab")
		)
		(fp_line
			(start 3.4036 -0.6731)
			(end 3.4036 6.1341)
			(stroke
				(width 0.1)
				(type default)
			)
			(layer "F.Fab")
		)
		(pad "1" smd rect
			(at 0 0 270)
			(size 3.556 3.175)
			(layers "F.Cu" "F.Mask" "F.Paste")
			(net "VR_PVPP_DEF_PHASE")
		)
		(pad "2" smd rect
			(at 0 5.461 270)
			(size 3.556 3.175)
			(layers "F.Cu" "F.Mask" "F.Paste")
			(net "PVPP_DEF")
		)
	)
	(footprint ""
		(layer "F.Cu")
		(at 252.1585 -149.8092 -90)
		(property "Reference" "C5A3"
			(at 1.848866 0.752348 270)
			(unlocked yes)
			(layer "F.SilkS")
			(effects
				(font
					(size 1.27 0.9652)
					(thickness 0.1524)
				)
			)
		)
		(property "Value" ""
			(at 0 0 270)
			(layer "F.Fab")
			(effects
				(font
					(size 1.27 1.27)
				)
			)
		)
		(duplicate_pad_numbers_are_jumpers no)
		(fp_rect
			(start -0.500126 1.598422)
			(end 0.500126 -0.201422)
			(stroke
				(width 0)
				(type default)
			)
			(fill no)
			(layer "F.CrtYd")
		)
		(fp_line
			(start -0.500126 1.598422)
			(end -0.500126 -0.201422)
			(stroke
				(width 0.1)
				(type default)
			)
			(layer "F.Fab")
		)
		(fp_line
			(start 0.500126 1.598422)
			(end -0.500126 1.598422)
			(stroke
				(width 0.1)
				(type default)
			)
			(layer "F.Fab")
		)
		(fp_line
			(start -0.500126 -0.201422)
			(end 0.500126 -0.201422)
			(stroke
				(width 0.1)
				(type default)
			)
			(layer "F.Fab")
		)
		(fp_line
			(start 0.500126 -0.201422)
			(end 0.500126 1.598422)
			(stroke
				(width 0.1)
				(type default)
			)
			(layer "F.Fab")
		)
		(pad "1" smd rect
			(at 0 0 180)
			(size 0.889 0.9906)
			(layers "F.Cu" "F.Mask" "F.Paste")
			(net "PVDDQ_DEF")
		)
		(pad "2" smd rect
			(at 0 1.397 180)
			(size 0.889 0.9906)
			(layers "F.Cu" "F.Mask" "F.Paste")
			(net "GND")
		)
		(zone
			(layer "F.Cu")
			(hatch none 0.5)
			(connect_pads
				(clearance 0)
			)
			(min_thickness 0.25)
			(keepout
				(tracks allowed)
				(vias not_allowed)
				(pads allowed)
				(copperpour not_allowed)
				(footprints allowed)
			)
			(placement
				(enabled no)
				(sheetname "")
			)
			(fill
				(thermal_gap 0.5)
				(thermal_bridge_width 0.5)
				(island_removal_mode 0)
			)
			(polygon
				(pts
					(xy 251.206 -150.3045) (xy 251.206 -149.3139) (xy 251.714 -149.3139) (xy 251.714 -150.3045)
				)
			)
		)
		(zone
			(layer "F.Cu")
			(hatch none 0.5)
			(connect_pads
				(clearance 0)
			)
			(min_thickness 0.25)
			(keepout
				(tracks not_allowed)
				(vias allowed)
				(pads allowed)
				(copperpour not_allowed)
				(footprints allowed)
			)
			(placement
				(enabled no)
				(sheetname "")
			)
			(fill
				(thermal_gap 0.5)
				(thermal_bridge_width 0.5)
				(island_removal_mode 0)
			)
			(polygon
				(pts
					(xy 251.206 -150.3045) (xy 251.206 -149.3139) (xy 251.714 -149.3139) (xy 251.714 -150.3045)
				)
			)
		)
	)
	(footprint ""
		(layer "F.Cu")
		(at 367.088928 -45.23232)
		(property "Reference" "U8F2"
			(at 10.3505 -2.88671 180)
			(unlocked yes)
			(layer "F.SilkS")
			(effects
				(font
					(size 0.7874 0.5842)
					(thickness 0.1524)
				)
				(justify left)
			)
		)
		(property "Value" ""
			(at 0 0 0)
			(layer "F.Fab")
			(effects
				(font
					(size 1.27 1.27)
				)
			)
		)
		(duplicate_pad_numbers_are_jumpers no)
		(fp_line
			(start -2.094738 -1.929892)
			(end 11.645392 -1.929892)
			(stroke
				(width 0.1524)
				(type default)
			)
			(layer "F.SilkS")
		)
		(fp_line
			(start -2.094738 10.819892)
			(end -2.094738 -1.929892)
			(stroke
				(width 0.1524)
				(type default)
			)
			(layer "F.SilkS")
		)
		(fp_line
			(start 11.645392 -1.929892)
			(end 11.645392 10.819892)
			(stroke
				(width 0.1524)
				(type default)
			)
			(layer "F.SilkS")
		)
		(fp_line
			(start 11.645392 10.819892)
			(end -2.094738 10.819892)
			(stroke
				(width 0.1524)
				(type default)
			)
			(layer "F.SilkS")
		)
		(fp_circle
			(center -2.568194 -2.286)
			(end -2.441194 -2.286)
			(stroke
				(width 0.762)
				(type default)
			)
			(fill no)
			(layer "F.SilkS")
		)
		(fp_rect
			(start -5.600954 12.260326)
			(end -2.094738 -3.284474)
			(stroke
				(width 0)
				(type default)
			)
			(fill no)
			(layer "F.CrtYd")
		)
		(fp_rect
			(start 11.645392 12.260326)
			(end 15.404846 -3.284474)
			(stroke
				(width 0)
				(type default)
			)
			(fill no)
			(layer "F.CrtYd")
		)
		(fp_poly
			(pts
				(xy -2.094738 10.819892) (xy 11.645392 10.819892) (xy 11.645392 -1.929892) (xy -2.094738 -1.929892)
			)
			(stroke
				(width 0)
				(type default)
			)
			(fill no)
			(layer "F.CrtYd")
		)
		(fp_poly
			(pts
				(xy 2.029968 -1.929892) (xy 2.629916 -3.32994) (xy 6.970014 -3.32994) (xy 7.569962 -1.929892)
			)
			(stroke
				(width 0)
				(type default)
			)
			(fill no)
			(layer "F.CrtYd")
		)
		(fp_poly
			(pts
				(xy 7.569962 10.819892) (xy 6.970014 12.21994) (xy 2.629916 12.21994) (xy 2.029968 10.819892)
			)
			(stroke
				(width 0)
				(type default)
			)
			(fill no)
			(layer "F.CrtYd")
		)
		(fp_line
			(start -2.094738 -1.929892)
			(end 11.645392 -1.929892)
			(stroke
				(width 0.1)
				(type default)
			)
			(layer "F.Fab")
		)
		(fp_line
			(start -2.094738 10.819892)
			(end -2.094738 -1.929892)
			(stroke
				(width 0.1)
				(type default)
			)
			(layer "F.Fab")
		)
		(fp_line
			(start 2.029968 -1.929892)
			(end 2.629916 -3.32994)
			(stroke
				(width 0.1)
				(type default)
			)
			(layer "F.Fab")
		)
		(fp_line
			(start 2.629916 -3.32994)
			(end 6.970014 -3.32994)
			(stroke
				(width 0.1)
				(type default)
			)
			(layer "F.Fab")
		)
		(fp_line
			(start 2.629916 12.21994)
			(end 2.029968 10.819892)
			(stroke
				(width 0.1)
				(type default)
			)
			(layer "F.Fab")
		)
		(fp_line
			(start 6.970014 -3.32994)
			(end 7.569962 -1.929892)
			(stroke
				(width 0.1)
				(type default)
			)
			(layer "F.Fab")
		)
		(fp_line
			(start 6.970014 12.21994)
			(end 2.629916 12.21994)
			(stroke
				(width 0.1)
				(type default)
			)
			(layer "F.Fab")
		)
		(fp_line
			(start 7.569962 10.819892)
			(end 6.970014 12.21994)
			(stroke
				(width 0.1)
				(type default)
			)
			(layer "F.Fab")
		)
		(fp_line
			(start 11.645392 -1.929892)
			(end 11.645392 10.819892)
			(stroke
				(width 0.1)
				(type default)
			)
			(layer "F.Fab")
		)
		(fp_line
			(start 11.645392 10.819892)
			(end -2.094738 10.819892)
			(stroke
				(width 0.1)
				(type default)
			)
			(layer "F.Fab")
		)
		(fp_circle
			(center -2.645918 -0.940054)
			(end -2.518918 -0.940054)
			(stroke
				(width 0.254)
				(type default)
			)
			(fill no)
			(layer "F.Fab")
		)
		(fp_text user "8"
			(at -1.498854 11.547348 90)
			(unlocked yes)
			(layer "F.SilkS")
			(effects
				(font
					(size 0.7874 0.5842)
					(thickness 0.1524)
				)
				(justify left)
			)
		)
		(fp_text user "9"
			(at 9.397746 11.529822 90)
			(unlocked yes)
			(layer "F.SilkS")
			(effects
				(font
					(size 0.7874 0.5842)
					(thickness 0.1524)
				)
				(justify left)
			)
		)
		(fp_text user "16"
			(at 12.40917 0.31496 90)
			(unlocked yes)
			(layer "F.SilkS")
			(effects
				(font
					(size 0.7874 0.5842)
					(thickness 0.1524)
				)
				(justify left)
			)
		)
		(fp_text user "8"
			(at -2.4257 9.04621 0)
			(unlocked yes)
			(layer "F.Fab")
			(effects
				(font
					(size 0.635 0.635)
					(thickness 0.1524)
				)
				(justify left)
			)
		)
		(fp_text user "16"
			(at 11.646916 0.367792 0)
			(unlocked yes)
			(layer "F.Fab")
			(effects
				(font
					(size 0.254 0.254)
					(thickness 0.000001)
				)
				(justify left)
			)
		)
		(fp_text user "9"
			(at 11.862054 9.20369 0)
			(unlocked yes)
			(layer "F.Fab")
			(effects
				(font
					(size 0.254 0.254)
					(thickness 0.000001)
				)
				(justify left)
			)
		)
		(pad "1" smd rect
			(at 0 0)
			(size 1.9304 0.635)
			(layers "F.Cu" "F.Mask" "F.Paste")
			(net "PU_SPI_BMC_BT_HOLD_N")
		)
		(pad "2" smd rect
			(at 0 1.27)
			(size 1.9304 0.635)
			(layers "F.Cu" "F.Mask" "F.Paste")
			(net "P3V3_STBY")
		)
		(pad "3" smd rect
			(at 0 2.54)
			(size 1.9304 0.635)
			(layers "F.Cu" "F.Mask" "F.Paste")
			(net "PU_SPI_FLASH_RESET_2_N")
		)
		(pad "4" smd rect
			(at 0 3.81)
			(size 1.9304 0.635)
			(layers "F.Cu" "F.Mask" "F.Paste")
			(net "TP_SPI_2_0")
		)
		(pad "5" smd rect
			(at 0 5.08)
			(size 1.9304 0.635)
			(layers "F.Cu" "F.Mask" "F.Paste")
			(net "TP_SPI_2_1")
		)
		(pad "6" smd rect
			(at 0 6.35)
			(size 1.9304 0.635)
			(layers "F.Cu" "F.Mask" "F.Paste")
			(net "TP_SPI_2_2")
		)
		(pad "7" smd rect
			(at 0 7.62)
			(size 1.9304 0.635)
			(layers "F.Cu" "F.Mask" "F.Paste")
			(net "SPI_BMC_BT_CS_N")
		)
		(pad "8" smd rect
			(at 0 8.89)
			(size 1.9304 0.635)
			(layers "F.Cu" "F.Mask" "F.Paste")
			(net "SPI_BMC_BT_DI_R")
		)
		(pad "9" smd rect
			(at 9.5504 8.89)
			(size 1.9304 0.635)
			(layers "F.Cu" "F.Mask" "F.Paste")
			(net "PU_SPI_BMC_BT_WP_N")
		)
		(pad "10" smd rect
			(at 9.5504 7.62)
			(size 1.9304 0.635)
			(layers "F.Cu" "F.Mask" "F.Paste")
			(net "GND")
		)
		(pad "11" smd rect
			(at 9.5504 6.35)
			(size 1.9304 0.635)
			(layers "F.Cu" "F.Mask" "F.Paste")
			(net "TP_SPI_2_3")
		)
		(pad "12" smd rect
			(at 9.5504 5.08)
			(size 1.9304 0.635)
			(layers "F.Cu" "F.Mask" "F.Paste")
			(net "TP_SPI_2_4")
		)
		(pad "13" smd rect
			(at 9.5504 3.81)
			(size 1.9304 0.635)
			(layers "F.Cu" "F.Mask" "F.Paste")
			(net "TP_SPI_2_5")
		)
		(pad "14" smd rect
			(at 9.5504 2.54)
			(size 1.9304 0.635)
			(layers "F.Cu" "F.Mask" "F.Paste")
			(net "TP_SPI_2_6")
		)
		(pad "15" smd rect
			(at 9.5504 1.27)
			(size 1.9304 0.635)
			(layers "F.Cu" "F.Mask" "F.Paste")
			(net "SPI_BMC_BT_DO")
		)
		(pad "16" smd rect
			(at 9.5504 0)
			(size 1.9304 0.635)
			(layers "F.Cu" "F.Mask" "F.Paste")
			(net "SPI_BMC_BT_CLK")
		)
	)
)
